FILE_TYPE = MACRO_DRAWING;
SET COLOR_WIRE YELLOW;
SET COLOR_PROP ORANGE;
SET COLOR_DOT WHITE;
SET COLOR_ARC YELLOW;
SET COLOR_BODY GREEN;
SET COLOR_NOTE PURPLE;
SET PROP_DISPLAY VALUE;
SET PAGE_NUMBER P183;
FORCEADD PCA9306DP1..1
R 2
(725 3400);
FORCEPROP 1 LAST PART_NUMBER AL009306K04
J 2
(924 3650);
DISPLAY 0.723404 (924 3650);
PAINT GREEN (924 3650);
DISPLAY INVISIBLE (924 3650);
FORCEPROP 2 LAST VALUE PCA9306DP1
J 2
(950 3900);
DISPLAY 1.021277 (950 3900);
FORCEPROP 2 LAST PART_TYPE SMLF
J 2
(950 3950);
DISPLAY 1.021277 (950 3950);
FORCEPROP 1 LAST MATERIAL IC
J 2
(924 3600);
DISPLAY 0.723404 (924 3600);
PAINT GREEN (924 3600);
FORCEPROP 1 LAST $LOCATION U98
J 2
(925 3705);
DISPLAY 0.680851 (925 3705);
PAINT GREEN (925 3705);
FORCEPROP 0 LASTPIN (1075 3275) $PN 8
J 0
(1085 3285);
DISPLAY 0.680851 (1085 3285);
PAINT MONO (1085 3285);
FORCEPROP 0 LASTPIN (475 3275) $PN 1
J 2
(465 3285);
DISPLAY 0.680851 (465 3285);
PAINT MONO (465 3285);
FORCEPROP 0 LASTPIN (1075 3375) $PN 3
J 0
(1085 3385);
DISPLAY 0.680851 (1085 3385);
PAINT MONO (1085 3385);
FORCEPROP 0 LASTPIN (375 3375) $PN 6
J 2
(365 3385);
DISPLAY 0.680851 (365 3385);
PAINT MONO (365 3385);
FORCEPROP 0 LASTPIN (1075 3425) $PN 4
J 0
(1085 3435);
DISPLAY 0.680851 (1085 3435);
PAINT MONO (1085 3435);
FORCEPROP 0 LASTPIN (375 3425) $PN 5
J 2
(365 3435);
DISPLAY 0.680851 (365 3435);
PAINT MONO (365 3435);
FORCEPROP 0 LASTPIN (1075 3525) $PN 2
J 0
(1085 3535);
DISPLAY 0.680851 (1085 3535);
PAINT MONO (1085 3535);
FORCEPROP 0 LASTPIN (375 3525) $PN 7
J 2
(365 3535);
DISPLAY 0.680851 (365 3535);
PAINT MONO (365 3535);
FORCEPROP 1 LAST PATH I27
J 2
(725 3400);
DISPLAY 0.723404 (725 3400);
PAINT GREEN (725 3400);
DISPLAY INVISIBLE (725 3400);
FORCEPROP 1 LAST CDS_LMAN_SYM_OUTLINE -200,175,200,-175
J 2
(725 3400);
DISPLAY 0.468085 (725 3400);
PAINT GREEN (725 3400);
DISPLAY INVISIBLE (725 3400);
FORCEPROP 1 LAST NEEDS_NO_SIZE TRUE
J 2
(725 3399);
DISPLAY 0.468085 (725 3399);
PAINT GREEN (725 3399);
DISPLAY INVISIBLE (725 3399);
FORCEPROP 2 LAST CDS_LIB pure_quanta
J 0
(725 3400);
DISPLAY INVISIBLE (725 3400);
FORCEPROP 2 LAST CDS_LOCATION U98
J 0
(950 4000);
DISPLAY 1.021277 (950 4000);
DISPLAY INVISIBLE (950 4000);
FORCEPROP 0 LAST $SEC 1
J 0
(950 4000);
DISPLAY 0.680851 (950 4000);
PAINT MONO (950 4000);
DISPLAY INVISIBLE (950 4000);
FORCEPROP 2 LAST CDS_SEC 1
J 0
(950 4000);
DISPLAY 1.021277 (950 4000);
DISPLAY INVISIBLE (950 4000);
FORCEADD Q_CAP..1
(1400 3800);
FORCEPROP 1 LAST PART_NUMBER CH4104K1B00
J 0
(1450 3650);
DISPLAY 0.510638 (1450 3650);
DISPLAY INVISIBLE (1450 3650);
FORCEPROP 1 LAST VALUE 0.1UF
J 0
(1450 3850);
DISPLAY 0.510638 (1450 3850);
FORCEPROP 1 LAST MATERIAL X7R
J 0
(1450 3700);
DISPLAY 0.510638 (1450 3700);
FORCEPROP 1 LAST VOLTAGE 25V
J 0
(1450 3800);
DISPLAY 0.510638 (1450 3800);
FORCEPROP 1 LAST TOLERANCE 10%
J 0
(1450 3750);
DISPLAY 0.510638 (1450 3750);
FORCEPROP 1 LAST PACK_TYPE 0402
J 0
(1450 3600);
DISPLAY 0.510638 (1450 3600);
FORCEPROP 1 LAST $LOCATION C1323
J 0
(1450 3900);
DISPLAY 0.978723 (1450 3900);
FORCEPROP 1 LASTPIN (1400 3900) $PN 1
J 0
(1410 3880);
DISPLAY 0.787234 (1410 3880);
FORCEPROP 1 LASTPIN (1400 3700) $PN 2
J 0
(1410 3680);
DISPLAY 0.787234 (1410 3680);
FORCEPROP 1 LAST PATH I28
J 0
(1450 3950);
DISPLAY 0.978723 (1450 3950);
PAINT WHITE (1450 3950);
DISPLAY INVISIBLE (1450 3950);
FORCEPROP 2 LAST CDS_LIB pure_quanta
J 0
(1400 3800);
PAINT MONO (1400 3800);
DISPLAY INVISIBLE (1400 3800);
FORCEPROP 2 LAST CDS_LOCATION C1323
J 0
(1450 4000);
DISPLAY 1.021277 (1450 4000);
DISPLAY INVISIBLE (1450 4000);
FORCEPROP 2 LAST $SEC 1
J 0
(1450 4000);
DISPLAY 0.680851 (1450 4000);
PAINT MONO (1450 4000);
DISPLAY INVISIBLE (1450 4000);
FORCEPROP 2 LAST CDS_SEC 1
J 0
(1450 4000);
DISPLAY 1.021277 (1450 4000);
DISPLAY INVISIBLE (1450 4000);
FORCEADD UNIVERSAL_POWER..1
(1225 4100);
FORCEPROP 3 LASTPIN (1225 4050) SIG_NAME P1V8_PCH_AUX\g
J 0
(1235 4060);
DISPLAY 0.659574 (1235 4060);
PAINT MONO (1235 4060);
DISPLAY INVISIBLE (1235 4060);
FORCEPROP 1 LAST HDL_POWER P1V8_PCH_AUX
J 1
(1225 4150);
DISPLAY 0.872340 (1225 4150);
PAINT GREEN (1225 4150);
FORCEPROP 1 LAST PATH I29
J 0
(1275 4125);
DISPLAY 0.872340 (1275 4125);
PAINT AQUA (1275 4125);
DISPLAY INVISIBLE (1275 4125);
FORCEPROP 2 LAST CDS_LIB logical_power
J 0
(1225 4100);
PAINT MONO (1225 4100);
DISPLAY INVISIBLE (1225 4100);
FORCEADD UNIVERSAL_POWER..1
(-2100 225);
FORCEPROP 3 LASTPIN (-2100 175) SIG_NAME P3V3_AUX\g
J 0
(-2090 185);
DISPLAY 0.659574 (-2090 185);
PAINT MONO (-2090 185);
DISPLAY INVISIBLE (-2090 185);
FORCEPROP 1 LAST HDL_POWER P3V3_AUX
J 1
(-2100 275);
DISPLAY 0.872340 (-2100 275);
PAINT GREEN (-2100 275);
FORCEPROP 1 LAST PATH I3
J 0
(-2050 250);
DISPLAY 0.872340 (-2050 250);
PAINT AQUA (-2050 250);
DISPLAY INVISIBLE (-2050 250);
FORCEPROP 2 LAST CDS_LIB logical_power
J 0
(-2100 225);
PAINT MONO (-2100 225);
DISPLAY INVISIBLE (-2100 225);
FORCEADD UNIVERSAL_GND..1
(1400 3575);
FORCEPROP 3 LASTPIN (1400 3625) SIG_NAME GND\g
J 0
(1410 3635);
DISPLAY 0.659574 (1410 3635);
PAINT MONO (1410 3635);
DISPLAY INVISIBLE (1410 3635);
FORCEPROP 1 LAST PATH I30
J 0
(1475 3575);
DISPLAY 0.872340 (1475 3575);
PAINT AQUA (1475 3575);
DISPLAY INVISIBLE (1475 3575);
FORCEPROP 1 LAST HDL_POWER GND
J 1
(1425 3500);
DISPLAY 0.872340 (1425 3500);
PAINT GREEN (1425 3500);
DISPLAY INVISIBLE (1425 3500);
FORCEPROP 2 LAST CDS_LIB logical_power
J 0
(1400 3575);
PAINT MONO (1400 3575);
DISPLAY INVISIBLE (1400 3575);
FORCEADD UNIVERSAL_GND..1
(350 3150);
FORCEPROP 3 LASTPIN (350 3200) SIG_NAME GND\g
J 0
(360 3210);
DISPLAY 0.659574 (360 3210);
PAINT MONO (360 3210);
DISPLAY INVISIBLE (360 3210);
FORCEPROP 1 LAST PATH I38
J 0
(425 3150);
DISPLAY 0.872340 (425 3150);
PAINT AQUA (425 3150);
DISPLAY INVISIBLE (425 3150);
FORCEPROP 2 LAST CDS_LIB logical_power
J 0
(350 3150);
PAINT MONO (350 3150);
DISPLAY INVISIBLE (350 3150);
FORCEPROP 1 LAST HDL_POWER GND
J 1
(375 3075);
DISPLAY 0.872340 (375 3075);
PAINT GREEN (375 3075);
DISPLAY INVISIBLE (375 3075);
FORCEADD Q_RES..2
(2250 3775);
FORCEPROP 1 LAST PART_NUMBER CS24702JB10
J 0
(2290 3600);
DISPLAY 0.638298 (2290 3600);
DISPLAY INVISIBLE (2290 3600);
FORCEPROP 1 LAST VALUE 4.7K
J 0
(2295 3850);
DISPLAY 0.638298 (2295 3850);
FORCEPROP 1 LAST TOLERANCE 5%
J 0
(2295 3800);
DISPLAY 0.638298 (2295 3800);
FORCEPROP 1 LAST PACK_TYPE 0402LF
J 0
(2290 3650);
DISPLAY 0.638298 (2290 3650);
FORCEPROP 1 LAST MATERIAL CHIP
J 0
(2290 3700);
DISPLAY 0.638298 (2290 3700);
FORCEPROP 1 LAST WATTAGE 1/16W
J 0
(2290 3750);
DISPLAY 0.638298 (2290 3750);
FORCEPROP 1 LAST $LOCATION R1702
J 0
(2295 3900);
DISPLAY 0.638298 (2295 3900);
FORCEPROP 1 LASTPIN (2250 3875) $PN 1
J 0
(2255 3837);
DISPLAY 0.787234 (2255 3837);
FORCEPROP 1 LASTPIN (2250 3675) $PN 2
J 0
(2255 3685);
DISPLAY 0.787234 (2255 3685);
FORCEPROP 1 LAST PATH I43
J 0
(2300 3950);
DISPLAY 0.978723 (2300 3950);
PAINT WHITE (2300 3950);
DISPLAY INVISIBLE (2300 3950);
FORCEPROP 2 LAST CDS_LIB pure_quanta
J 0
(2250 3775);
PAINT MONO (2250 3775);
DISPLAY INVISIBLE (2250 3775);
FORCEPROP 2 LAST CDS_LOCATION R1702
J 0
(2300 4000);
DISPLAY 1.021277 (2300 4000);
DISPLAY INVISIBLE (2300 4000);
FORCEPROP 2 LAST $SEC 1
J 0
(2300 4000);
DISPLAY 0.680851 (2300 4000);
PAINT MONO (2300 4000);
DISPLAY INVISIBLE (2300 4000);
FORCEPROP 2 LAST CDS_SEC 1
J 0
(2300 4000);
DISPLAY 1.021277 (2300 4000);
DISPLAY INVISIBLE (2300 4000);
FORCEADD Q_RES..2
(2500 3775);
FORCEPROP 1 LAST PART_NUMBER CS24702JB10
J 0
(2540 3600);
DISPLAY 0.638298 (2540 3600);
DISPLAY INVISIBLE (2540 3600);
FORCEPROP 1 LAST PACK_TYPE 0402LF
J 0
(2540 3650);
DISPLAY 0.638298 (2540 3650);
FORCEPROP 1 LAST MATERIAL CHIP
J 0
(2540 3700);
DISPLAY 0.638298 (2540 3700);
FORCEPROP 1 LAST TOLERANCE 5%
J 0
(2545 3800);
DISPLAY 0.638298 (2545 3800);
FORCEPROP 1 LAST VALUE 4.7K
J 0
(2545 3850);
DISPLAY 0.638298 (2545 3850);
FORCEPROP 1 LAST WATTAGE 1/16W
J 0
(2540 3750);
DISPLAY 0.638298 (2540 3750);
FORCEPROP 1 LAST $LOCATION R1703
J 0
(2545 3900);
DISPLAY 0.638298 (2545 3900);
FORCEPROP 1 LASTPIN (2500 3875) $PN 1
J 0
(2505 3837);
DISPLAY 0.787234 (2505 3837);
FORCEPROP 1 LASTPIN (2500 3675) $PN 2
J 0
(2505 3685);
DISPLAY 0.787234 (2505 3685);
FORCEPROP 1 LAST PATH I45
J 0
(2550 3950);
DISPLAY 0.978723 (2550 3950);
PAINT WHITE (2550 3950);
DISPLAY INVISIBLE (2550 3950);
FORCEPROP 2 LAST CDS_LIB pure_quanta
J 0
(2500 3775);
PAINT MONO (2500 3775);
DISPLAY INVISIBLE (2500 3775);
FORCEPROP 2 LAST CDS_LOCATION R1703
J 0
(2550 4000);
DISPLAY 1.021277 (2550 4000);
DISPLAY INVISIBLE (2550 4000);
FORCEPROP 2 LAST $SEC 1
J 0
(2550 4000);
DISPLAY 0.680851 (2550 4000);
PAINT MONO (2550 4000);
DISPLAY INVISIBLE (2550 4000);
FORCEPROP 2 LAST CDS_SEC 1
J 0
(2550 4000);
DISPLAY 1.021277 (2550 4000);
DISPLAY INVISIBLE (2550 4000);
FORCEADD UNIVERSAL_POWER..1
(2250 4100);
FORCEPROP 3 LASTPIN (2250 4050) SIG_NAME P1V8_PCH_AUX\g
J 0
(2260 4060);
DISPLAY 0.659574 (2260 4060);
PAINT MONO (2260 4060);
DISPLAY INVISIBLE (2260 4060);
FORCEPROP 1 LAST HDL_POWER P1V8_PCH_AUX
J 1
(2250 4150);
DISPLAY 0.872340 (2250 4150);
PAINT GREEN (2250 4150);
FORCEPROP 1 LAST PATH I47
J 0
(2300 4125);
DISPLAY 0.872340 (2300 4125);
PAINT AQUA (2300 4125);
DISPLAY INVISIBLE (2300 4125);
FORCEPROP 2 LAST CDS_LIB logical_power
J 0
(2250 4100);
PAINT MONO (2250 4100);
DISPLAY INVISIBLE (2250 4100);
FORCEADD Q_RES..2
(-2100 -200);
FORCEPROP 1 LAST PART_NUMBER CS22212FB06
J 0
(-2060 -325);
DISPLAY 0.978723 (-2060 -325);
DISPLAY INVISIBLE (-2060 -325);
FORCEPROP 1 LAST WATTAGE 1/16W
J 0
(-2060 -225);
DISPLAY 0.978723 (-2060 -225);
FORCEPROP 1 LAST PACK_TYPE 0402LF
J 0
(-2060 -375);
DISPLAY 0.978723 (-2060 -375);
FORCEPROP 1 LAST VALUE 2.21K
J 0
(-2055 -125);
DISPLAY 0.978723 (-2055 -125);
FORCEPROP 1 LAST TOLERANCE 1%
J 0
(-2055 -175);
DISPLAY 0.978723 (-2055 -175);
FORCEPROP 1 LAST MATERIAL EMPTY
J 0
(-2060 -275);
DISPLAY 0.978723 (-2060 -275);
PAINT RED (-2060 -275);
FORCEPROP 1 LAST $LOCATION R1271
J 0
(-2055 -75);
DISPLAY 0.978723 (-2055 -75);
FORCEPROP 1 LASTPIN (-2100 -100) $PN 1
J 0
(-2095 -138);
DISPLAY 0.787234 (-2095 -138);
PAINT MONO (-2095 -138);
FORCEPROP 1 LASTPIN (-2100 -300) $PN 2
J 0
(-2095 -290);
DISPLAY 0.787234 (-2095 -290);
PAINT MONO (-2095 -290);
FORCEPROP 2 LAST CDS_LIB pure_quanta
J 0
(-2100 -200);
DISPLAY INVISIBLE (-2100 -200);
FORCEPROP 1 LAST PATH I5
J 0
(-2050 -25);
DISPLAY 0.978723 (-2050 -25);
PAINT WHITE (-2050 -25);
DISPLAY INVISIBLE (-2050 -25);
FORCEPROP 2 LAST CDS_LOCATION R1271
J 0
(-2050 25);
DISPLAY 1.021277 (-2050 25);
DISPLAY INVISIBLE (-2050 25);
FORCEPROP 0 LAST $SEC 1
J 0
(-2050 -25);
DISPLAY 0.680851 (-2050 -25);
PAINT MONO (-2050 -25);
DISPLAY INVISIBLE (-2050 -25);
FORCEPROP 2 LAST CDS_SEC 1
J 0
(-2050 25);
DISPLAY 1.021277 (-2050 25);
DISPLAY INVISIBLE (-2050 25);
FORCEADD UNIVERSAL_POWER..1
(0 4125);
FORCEPROP 3 LASTPIN (0 4075) SIG_NAME P3V3_AUX\g
J 0
(10 4085);
DISPLAY 0.659574 (10 4085);
PAINT MONO (10 4085);
DISPLAY INVISIBLE (10 4085);
FORCEPROP 1 LAST HDL_POWER P3V3_AUX
J 1
(0 4175);
DISPLAY 0.872340 (0 4175);
PAINT GREEN (0 4175);
FORCEPROP 1 LAST PATH I51
J 0
(50 4150);
DISPLAY 0.872340 (50 4150);
PAINT AQUA (50 4150);
DISPLAY INVISIBLE (50 4150);
FORCEPROP 2 LAST CDS_LIB logical_power
J 0
(0 4125);
PAINT MONO (0 4125);
DISPLAY INVISIBLE (0 4125);
FORCEADD Q_CAP..1
R 2
(-425 3775);
FORCEPROP 1 LAST PART_NUMBER CH4104K1B00
J 2
(-475 3625);
DISPLAY 0.510638 (-475 3625);
DISPLAY INVISIBLE (-475 3625);
FORCEPROP 1 LAST TOLERANCE 10%
J 2
(-475 3725);
DISPLAY 0.510638 (-475 3725);
FORCEPROP 1 LAST VALUE 0.1UF
J 2
(-475 3825);
DISPLAY 0.510638 (-475 3825);
FORCEPROP 1 LAST PACK_TYPE 0402
J 2
(-475 3575);
DISPLAY 0.510638 (-475 3575);
FORCEPROP 1 LAST VOLTAGE 25V
J 2
(-475 3775);
DISPLAY 0.510638 (-475 3775);
FORCEPROP 1 LAST MATERIAL X7R
J 2
(-475 3675);
DISPLAY 0.510638 (-475 3675);
FORCEPROP 1 LAST $LOCATION C1305
J 2
(-475 3875);
DISPLAY 0.978723 (-475 3875);
FORCEPROP 1 LASTPIN (-425 3875) $PN 1
J 2
(-435 3855);
DISPLAY 0.787234 (-435 3855);
FORCEPROP 1 LASTPIN (-425 3675) $PN 2
J 2
(-435 3655);
DISPLAY 0.787234 (-435 3655);
FORCEPROP 1 LAST PATH I52
J 2
(-475 3925);
DISPLAY 0.978723 (-475 3925);
PAINT WHITE (-475 3925);
DISPLAY INVISIBLE (-475 3925);
FORCEPROP 2 LAST CDS_LIB pure_quanta
J 2
(-425 3775);
PAINT MONO (-425 3775);
DISPLAY INVISIBLE (-425 3775);
FORCEPROP 2 LAST CDS_LOCATION C1305
J 0
(-475 3975);
DISPLAY 1.021277 (-475 3975);
DISPLAY INVISIBLE (-475 3975);
FORCEPROP 2 LAST $SEC 1
J 0
(-475 3975);
DISPLAY 0.680851 (-475 3975);
PAINT MONO (-475 3975);
DISPLAY INVISIBLE (-475 3975);
FORCEPROP 2 LAST CDS_SEC 1
J 0
(-475 3975);
DISPLAY 1.021277 (-475 3975);
DISPLAY INVISIBLE (-475 3975);
FORCEADD UNIVERSAL_GND..1
(-425 3575);
FORCEPROP 3 LASTPIN (-425 3625) SIG_NAME GND\g
J 0
(-415 3635);
DISPLAY 0.659574 (-415 3635);
PAINT MONO (-415 3635);
DISPLAY INVISIBLE (-415 3635);
FORCEPROP 1 LAST PATH I53
J 0
(-350 3575);
DISPLAY 0.872340 (-350 3575);
PAINT AQUA (-350 3575);
DISPLAY INVISIBLE (-350 3575);
FORCEPROP 1 LAST HDL_POWER GND
J 1
(-400 3500);
DISPLAY 0.872340 (-400 3500);
PAINT GREEN (-400 3500);
DISPLAY INVISIBLE (-400 3500);
FORCEPROP 2 LAST CDS_LIB logical_power
J 0
(-425 3575);
PAINT MONO (-425 3575);
DISPLAY INVISIBLE (-425 3575);
FORCEADD OFFPAGE..6
(-1000 3425);
FORCEPROP 2 LAST $XR0 231 
J 0
(-1280 3425);
DISPLAY 0.638298 (-1280 3425);
PAINT MONO (-1280 3425);
FORCEPROP 2 LAST PATH I54
J 0
(-1275 3475);
DISPLAY 1.021277 (-1275 3475);
DISPLAY INVISIBLE (-1275 3475);
FORCEPROP 1 LAST COMMENT_BODY TRUE
J 0
(-900 3350);
DISPLAY 0.872340 (-900 3350);
PAINT GREEN (-900 3350);
DISPLAY INVISIBLE (-900 3350);
FORCEPROP 1 LAST OFFPAGE TRUE
J 0
(-675 3300);
DISPLAY 0.872340 (-675 3300);
DISPLAY INVISIBLE (-675 3300);
FORCEPROP 2 LAST CDS_LIB standard
J 0
(-1000 3425);
PAINT MONO (-1000 3425);
DISPLAY INVISIBLE (-1000 3425);
FORCEADD OFFPAGE..1
(-1000 3375);
FORCEPROP 2 LAST $XR0 231 
J 0
(-1282 3375);
DISPLAY 0.638298 (-1282 3375);
PAINT MONO (-1282 3375);
FORCEPROP 2 LAST PATH I55
J 0
(-1275 3425);
DISPLAY 1.021277 (-1275 3425);
DISPLAY INVISIBLE (-1275 3425);
FORCEPROP 1 LAST COMMENT_BODY TRUE
J 0
(-875 3275);
DISPLAY 0.872340 (-875 3275);
PAINT GREEN (-875 3275);
DISPLAY INVISIBLE (-875 3275);
FORCEPROP 1 LAST OFFPAGE TRUE
J 0
(-675 3250);
DISPLAY 0.872340 (-675 3250);
DISPLAY INVISIBLE (-675 3250);
FORCEPROP 2 LAST CDS_LIB standard
J 0
(-1000 3375);
PAINT MONO (-1000 3375);
DISPLAY INVISIBLE (-1000 3375);
FORCEADD Q_RES..1
(2800 3425);
FORCEPROP 1 LAST PART_NUMBER CS03322FB03
J 0
(2675 3475);
DISPLAY 0.404255 (2675 3475);
DISPLAY INVISIBLE (2675 3475);
FORCEPROP 1 LAST MATERIAL CHIP
J 0
(3100 3425);
DISPLAY 0.510638 (3100 3425);
FORCEPROP 1 LAST VALUE 33.2
J 2
(3000 3425);
DISPLAY 0.510638 (3000 3425);
FORCEPROP 1 LAST WATTAGE 1/16W
J 2
(2900 3525);
DISPLAY 0.404255 (2900 3525);
FORCEPROP 1 LAST PACK_TYPE 0402LF
J 0
(2675 3525);
DISPLAY 0.404255 (2675 3525);
FORCEPROP 1 LAST TOLERANCE 1%
J 0
(3025 3425);
DISPLAY 0.510638 (3025 3425);
FORCEPROP 1 LAST $LOCATION R2410
J 0
(2575 3425);
DISPLAY 0.638298 (2575 3425);
FORCEPROP 1 LASTPIN (2700 3425) $PN 1
J 0
(2712 3437);
DISPLAY 0.787234 (2712 3437);
PAINT MONO (2712 3437);
FORCEPROP 1 LASTPIN (2900 3425) $PN 2
J 0
(2862 3437);
DISPLAY 0.787234 (2862 3437);
PAINT MONO (2862 3437);
FORCEPROP 1 LAST PATH I65
J 0
(2750 3575);
DISPLAY 0.978723 (2750 3575);
PAINT WHITE (2750 3575);
DISPLAY INVISIBLE (2750 3575);
FORCEPROP 2 LAST CDS_LIB pure_quanta
J 0
(2800 3425);
DISPLAY INVISIBLE (2800 3425);
FORCEPROP 0 LAST CDS_LOCATION R2410
J 0
(2900 3550);
DISPLAY 1.021277 (2900 3550);
DISPLAY INVISIBLE (2900 3550);
FORCEPROP 0 LAST $SEC 1
J 0
(2900 3550);
DISPLAY 0.680851 (2900 3550);
PAINT MONO (2900 3550);
DISPLAY INVISIBLE (2900 3550);
FORCEPROP 0 LAST CDS_SEC 1
J 0
(2900 3550);
DISPLAY 1.021277 (2900 3550);
DISPLAY INVISIBLE (2900 3550);
FORCEADD Q_RES..1
(2800 3375);
FORCEPROP 1 LAST PART_NUMBER CS03322FB03
J 0
(2675 3425);
DISPLAY 0.404255 (2675 3425);
DISPLAY INVISIBLE (2675 3425);
FORCEPROP 1 LAST VALUE 33.2
J 2
(3000 3375);
DISPLAY 0.510638 (3000 3375);
FORCEPROP 1 LAST MATERIAL CHIP
J 0
(3100 3375);
DISPLAY 0.510638 (3100 3375);
FORCEPROP 1 LAST TOLERANCE 1%
J 0
(3025 3375);
DISPLAY 0.510638 (3025 3375);
FORCEPROP 1 LAST $LOCATION R2411
J 0
(2575 3375);
DISPLAY 0.638298 (2575 3375);
FORCEPROP 1 LASTPIN (2700 3375) $PN 1
J 0
(2712 3387);
DISPLAY 0.787234 (2712 3387);
PAINT MONO (2712 3387);
FORCEPROP 1 LASTPIN (2900 3375) $PN 2
J 0
(2862 3387);
DISPLAY 0.787234 (2862 3387);
PAINT MONO (2862 3387);
FORCEPROP 1 LAST PATH I66
J 0
(2750 3525);
DISPLAY 0.978723 (2750 3525);
PAINT WHITE (2750 3525);
DISPLAY INVISIBLE (2750 3525);
FORCEPROP 2 LAST CDS_LIB pure_quanta
J 0
(2800 3375);
DISPLAY INVISIBLE (2800 3375);
FORCEPROP 1 LAST PACK_TYPE 0402LF
J 0
(2675 3475);
DISPLAY 0.404255 (2675 3475);
DISPLAY INVISIBLE (2675 3475);
FORCEPROP 1 LAST WATTAGE 1/16W
J 2
(2900 3475);
DISPLAY 0.404255 (2900 3475);
DISPLAY INVISIBLE (2900 3475);
FORCEPROP 0 LAST CDS_LOCATION R2411
J 0
(2575 3425);
DISPLAY 1.021277 (2575 3425);
DISPLAY INVISIBLE (2575 3425);
FORCEPROP 0 LAST $SEC 1
J 0
(2575 3425);
DISPLAY 0.680851 (2575 3425);
PAINT MONO (2575 3425);
DISPLAY INVISIBLE (2575 3425);
FORCEPROP 0 LAST CDS_SEC 1
J 0
(2575 3425);
DISPLAY 1.021277 (2575 3425);
DISPLAY INVISIBLE (2575 3425);
FORCEADD OFFPAGE..3
(4125 3425);
FORCEPROP 2 LAST $XR0 190 
J 0
(4339 3425);
DISPLAY 0.638298 (4339 3425);
PAINT MONO (4339 3425);
FORCEPROP 2 LAST PATH I67
J 0
(4350 3475);
DISPLAY 1.021277 (4350 3475);
DISPLAY INVISIBLE (4350 3475);
FORCEPROP 2 LAST CDS_LIB standard
J 0
(4125 3425);
PAINT MONO (4125 3425);
DISPLAY INVISIBLE (4125 3425);
FORCEPROP 1 LAST OFFPAGE TRUE
J 0
(4450 3300);
DISPLAY 0.872340 (4450 3300);
PAINT GREEN (4450 3300);
DISPLAY INVISIBLE (4450 3300);
FORCEPROP 1 LAST COMMENT_BODY TRUE
J 0
(4075 3325);
DISPLAY 0.872340 (4075 3325);
PAINT GREEN (4075 3325);
DISPLAY INVISIBLE (4075 3325);
FORCEADD OFFPAGE..2
(4125 3375);
FORCEPROP 2 LAST $XR0 190 
J 0
(4344 3375);
DISPLAY 0.638298 (4344 3375);
PAINT MONO (4344 3375);
FORCEPROP 2 LAST PATH I68
J 0
(4350 3425);
DISPLAY 1.021277 (4350 3425);
DISPLAY INVISIBLE (4350 3425);
FORCEPROP 1 LAST COMMENT_BODY TRUE
J 0
(4080 3280);
DISPLAY 0.872340 (4080 3280);
PAINT GREEN (4080 3280);
DISPLAY INVISIBLE (4080 3280);
FORCEPROP 1 LAST OFFPAGE TRUE
J 0
(4450 3250);
DISPLAY 0.872340 (4450 3250);
PAINT GREEN (4450 3250);
DISPLAY INVISIBLE (4450 3250);
FORCEPROP 2 LAST CDS_LIB standard
J 0
(4125 3375);
DISPLAY INVISIBLE (4125 3375);
FORCEADD OFFPAGE..3
(-600 -675);
FORCEPROP 2 LAST $XR0 183 
J 0
(-386 -675);
DISPLAY 0.638298 (-386 -675);
PAINT MONO (-386 -675);
FORCEPROP 2 LAST CDS_LIB standard
J 0
(-600 -675);
PAINT MONO (-600 -675);
DISPLAY INVISIBLE (-600 -675);
FORCEPROP 2 LAST PATH I7
J 0
(475 -625);
DISPLAY 1.021277 (475 -625);
DISPLAY INVISIBLE (475 -625);
FORCEPROP 1 LAST COMMENT_BODY TRUE
J 0
(-650 -775);
DISPLAY 0.872340 (-650 -775);
PAINT GREEN (-650 -775);
DISPLAY INVISIBLE (-650 -775);
FORCEPROP 1 LAST OFFPAGE TRUE
J 0
(-275 -800);
DISPLAY 0.872340 (-275 -800);
PAINT GREEN (-275 -800);
DISPLAY INVISIBLE (-275 -800);
FORCEADD Q_RES..1
(2300 3100);
FORCEPROP 1 LAST PART_NUMBER CS42002FB05
J 0
(2200 3175);
DISPLAY 0.510638 (2200 3175);
DISPLAY INVISIBLE (2200 3175);
FORCEPROP 1 LAST MATERIAL EMPTY
J 0
(2600 3100);
DISPLAY 0.510638 (2600 3100);
PAINT RED (2600 3100);
FORCEPROP 1 LAST TOLERANCE 1%
J 0
(2525 3100);
DISPLAY 0.510638 (2525 3100);
FORCEPROP 1 LAST VALUE 200K
J 2
(2500 3100);
DISPLAY 0.510638 (2500 3100);
FORCEPROP 1 LAST WATTAGE 1/16W
J 2
(2500 3225);
DISPLAY 0.510638 (2500 3225);
FORCEPROP 1 LAST PACK_TYPE 0402LF
J 0
(2200 3225);
DISPLAY 0.510638 (2200 3225);
FORCEPROP 1 LAST $LOCATION R2476
J 0
(2075 3100);
DISPLAY 0.787234 (2075 3100);
FORCEPROP 1 LASTPIN (2200 3100) $PN 1
J 0
(2212 3112);
DISPLAY 0.787234 (2212 3112);
PAINT MONO (2212 3112);
FORCEPROP 1 LASTPIN (2400 3100) $PN 2
J 0
(2362 3112);
DISPLAY 0.787234 (2362 3112);
PAINT MONO (2362 3112);
FORCEPROP 1 LAST PATH I70
J 0
(2250 3250);
DISPLAY 0.978723 (2250 3250);
PAINT WHITE (2250 3250);
DISPLAY INVISIBLE (2250 3250);
FORCEPROP 2 LAST CDS_LIB pure_quanta
J 0
(2300 3100);
DISPLAY INVISIBLE (2300 3100);
FORCEPROP 0 LAST CDS_LOCATION R2476
J 0
(2500 3250);
DISPLAY 1.021277 (2500 3250);
DISPLAY INVISIBLE (2500 3250);
FORCEPROP 0 LAST $SEC 1
J 0
(2500 3250);
DISPLAY 0.680851 (2500 3250);
PAINT MONO (2500 3250);
DISPLAY INVISIBLE (2500 3250);
FORCEPROP 0 LAST CDS_SEC 1
J 0
(2500 3250);
DISPLAY 1.021277 (2500 3250);
DISPLAY INVISIBLE (2500 3250);
FORCEADD OFFPAGE..4
(3625 3100);
FORCEPROP 2 LAST $XR2 252 
J 0
(4051 3100);
DISPLAY 0.638298 (4051 3100);
PAINT MONO (4051 3100);
FORCEPROP 2 LAST $XR1 222 
J 0
(3931 3100);
DISPLAY 0.638298 (3931 3100);
PAINT MONO (3931 3100);
FORCEPROP 2 LAST $XR0 263 
J 0
(3811 3100);
DISPLAY 0.638298 (3811 3100);
PAINT MONO (3811 3100);
FORCEPROP 2 LAST PATH I71
J 0
(3850 3150);
DISPLAY 1.021277 (3850 3150);
DISPLAY INVISIBLE (3850 3150);
FORCEPROP 1 LAST COMMENT_BODY TRUE
J 0
(3600 3000);
DISPLAY 0.872340 (3600 3000);
PAINT GREEN (3600 3000);
DISPLAY INVISIBLE (3600 3000);
FORCEPROP 1 LAST OFFPAGE TRUE
J 0
(3950 2975);
DISPLAY 0.872340 (3950 2975);
DISPLAY INVISIBLE (3950 2975);
FORCEPROP 2 LAST CDS_LIB standard
J 0
(3625 3100);
DISPLAY INVISIBLE (3625 3100);
FORCEADD Q_RES..2
(0 3750);
FORCEPROP 1 LAST PART_NUMBER CS42002FB05
J 0
(40 3625);
DISPLAY 0.638298 (40 3625);
DISPLAY INVISIBLE (40 3625);
FORCEPROP 1 LAST TOLERANCE 1%
J 0
(45 3775);
DISPLAY 0.638298 (45 3775);
FORCEPROP 1 LAST PACK_TYPE 0402LF
J 0
(40 3575);
DISPLAY 0.638298 (40 3575);
FORCEPROP 1 LAST MATERIAL CHIP
J 0
(40 3675);
DISPLAY 0.638298 (40 3675);
FORCEPROP 1 LAST WATTAGE 1/16W
J 0
(40 3725);
DISPLAY 0.638298 (40 3725);
FORCEPROP 1 LAST VALUE 200K
J 0
(45 3825);
DISPLAY 0.638298 (45 3825);
FORCEPROP 1 LAST $LOCATION R1700
J 0
(45 3875);
DISPLAY 0.638298 (45 3875);
FORCEPROP 1 LASTPIN (0 3850) $PN 1
J 0
(5 3812);
DISPLAY 0.787234 (5 3812);
PAINT MONO (5 3812);
FORCEPROP 1 LASTPIN (0 3650) $PN 2
J 0
(5 3660);
DISPLAY 0.787234 (5 3660);
PAINT MONO (5 3660);
FORCEPROP 1 LAST PATH I72
J 0
(50 3925);
DISPLAY 0.978723 (50 3925);
PAINT WHITE (50 3925);
DISPLAY INVISIBLE (50 3925);
FORCEPROP 2 LAST CDS_LIB pure_quanta
J 0
(0 3750);
DISPLAY INVISIBLE (0 3750);
FORCEPROP 2 LAST CDS_LOCATION R1700
J 0
(50 3975);
DISPLAY 1.021277 (50 3975);
DISPLAY INVISIBLE (50 3975);
FORCEPROP 0 LAST $SEC 1
J 0
(50 3925);
DISPLAY 0.680851 (50 3925);
PAINT MONO (50 3925);
DISPLAY INVISIBLE (50 3925);
FORCEPROP 2 LAST CDS_SEC 1
J 0
(50 3975);
DISPLAY 1.021277 (50 3975);
DISPLAY INVISIBLE (50 3975);
FORCEADD OFFPAGE..3
(4050 1225);
FORCEPROP 2 LAST $XR0 191 
J 0
(4264 1225);
DISPLAY 0.638298 (4264 1225);
PAINT MONO (4264 1225);
FORCEPROP 2 LAST PATH I73
J 0
(4275 1275);
DISPLAY 1.021277 (4275 1275);
DISPLAY INVISIBLE (4275 1275);
FORCEPROP 1 LAST COMMENT_BODY TRUE
J 0
(4000 1125);
DISPLAY 0.872340 (4000 1125);
PAINT GREEN (4000 1125);
DISPLAY INVISIBLE (4000 1125);
FORCEPROP 1 LAST OFFPAGE TRUE
J 0
(4375 1100);
DISPLAY 0.872340 (4375 1100);
PAINT GREEN (4375 1100);
DISPLAY INVISIBLE (4375 1100);
FORCEPROP 2 LAST CDS_LIB standard
J 0
(4050 1225);
PAINT MONO (4050 1225);
DISPLAY INVISIBLE (4050 1225);
FORCEADD OFFPAGE..2
(4050 1125);
FORCEPROP 2 LAST $XR0 191 
J 0
(4239 1125);
DISPLAY 0.638298 (4239 1125);
PAINT MONO (4239 1125);
FORCEPROP 2 LAST PATH I74
J 0
(4275 1175);
DISPLAY 1.021277 (4275 1175);
DISPLAY INVISIBLE (4275 1175);
FORCEPROP 2 LAST CDS_LIB standard
J 0
(4050 1125);
DISPLAY INVISIBLE (4050 1125);
FORCEPROP 1 LAST OFFPAGE TRUE
J 0
(4375 1000);
DISPLAY 0.872340 (4375 1000);
PAINT GREEN (4375 1000);
DISPLAY INVISIBLE (4375 1000);
FORCEPROP 1 LAST COMMENT_BODY TRUE
J 0
(4005 1030);
DISPLAY 0.872340 (4005 1030);
PAINT GREEN (4005 1030);
DISPLAY INVISIBLE (4005 1030);
FORCEADD Q_RES..1
(2700 1225);
FORCEPROP 1 LAST PART_NUMBER CS03322FB03
J 0
(2575 1275);
DISPLAY 0.404255 (2575 1275);
DISPLAY INVISIBLE (2575 1275);
FORCEPROP 1 LAST WATTAGE 1/16W
J 2
(2800 1325);
DISPLAY 0.404255 (2800 1325);
FORCEPROP 1 LAST PACK_TYPE 0402LF
J 0
(2575 1325);
DISPLAY 0.404255 (2575 1325);
FORCEPROP 1 LAST VALUE 33.2
J 2
(2900 1225);
DISPLAY 0.510638 (2900 1225);
FORCEPROP 1 LAST MATERIAL CHIP
J 0
(3000 1225);
DISPLAY 0.510638 (3000 1225);
FORCEPROP 1 LAST TOLERANCE 1%
J 0
(2925 1225);
DISPLAY 0.510638 (2925 1225);
FORCEPROP 1 LAST $LOCATION R3533
J 0
(2475 1225);
DISPLAY 0.638298 (2475 1225);
FORCEPROP 1 LASTPIN (2600 1225) $PN 1
J 0
(2612 1237);
DISPLAY 0.787234 (2612 1237);
PAINT MONO (2612 1237);
FORCEPROP 1 LASTPIN (2800 1225) $PN 2
J 0
(2762 1237);
DISPLAY 0.787234 (2762 1237);
PAINT MONO (2762 1237);
FORCEPROP 1 LAST PATH I76
J 0
(2650 1375);
DISPLAY 0.978723 (2650 1375);
PAINT WHITE (2650 1375);
DISPLAY INVISIBLE (2650 1375);
FORCEPROP 2 LAST CDS_LIB pure_quanta
J 0
(2700 1225);
DISPLAY INVISIBLE (2700 1225);
FORCEPROP 0 LAST CDS_LOCATION R3533
J 0
(2800 1350);
DISPLAY 1.021277 (2800 1350);
DISPLAY INVISIBLE (2800 1350);
FORCEPROP 0 LAST $SEC 1
J 0
(2800 1350);
DISPLAY 0.680851 (2800 1350);
PAINT MONO (2800 1350);
DISPLAY INVISIBLE (2800 1350);
FORCEPROP 0 LAST CDS_SEC 1
J 0
(2800 1350);
DISPLAY 1.021277 (2800 1350);
DISPLAY INVISIBLE (2800 1350);
FORCEADD Q_RES..1
(2700 1125);
FORCEPROP 1 LAST PART_NUMBER CS03322FB03
J 0
(2575 1175);
DISPLAY 0.404255 (2575 1175);
DISPLAY INVISIBLE (2575 1175);
FORCEPROP 1 LAST TOLERANCE 1%
J 0
(2925 1125);
DISPLAY 0.510638 (2925 1125);
FORCEPROP 1 LAST VALUE 33.2
J 2
(2900 1125);
DISPLAY 0.510638 (2900 1125);
FORCEPROP 1 LAST MATERIAL CHIP
J 0
(3000 1125);
DISPLAY 0.510638 (3000 1125);
FORCEPROP 1 LAST $LOCATION R3534
J 0
(2475 1125);
DISPLAY 0.638298 (2475 1125);
FORCEPROP 1 LASTPIN (2600 1125) $PN 1
J 0
(2612 1137);
DISPLAY 0.787234 (2612 1137);
PAINT MONO (2612 1137);
FORCEPROP 1 LASTPIN (2800 1125) $PN 2
J 0
(2762 1137);
DISPLAY 0.787234 (2762 1137);
PAINT MONO (2762 1137);
FORCEPROP 1 LAST PATH I77
J 0
(2650 1275);
DISPLAY 0.978723 (2650 1275);
PAINT WHITE (2650 1275);
DISPLAY INVISIBLE (2650 1275);
FORCEPROP 1 LAST WATTAGE 1/16W
J 2
(2800 1225);
DISPLAY 0.404255 (2800 1225);
DISPLAY INVISIBLE (2800 1225);
FORCEPROP 1 LAST PACK_TYPE 0402LF
J 0
(2575 1225);
DISPLAY 0.404255 (2575 1225);
DISPLAY INVISIBLE (2575 1225);
FORCEPROP 2 LAST CDS_LIB pure_quanta
J 0
(2700 1125);
DISPLAY INVISIBLE (2700 1125);
FORCEPROP 0 LAST CDS_LOCATION R3534
J 0
(2475 1175);
DISPLAY 1.021277 (2475 1175);
DISPLAY INVISIBLE (2475 1175);
FORCEPROP 0 LAST $SEC 1
J 0
(2475 1175);
DISPLAY 0.680851 (2475 1175);
PAINT MONO (2475 1175);
DISPLAY INVISIBLE (2475 1175);
FORCEPROP 0 LAST CDS_SEC 1
J 0
(2475 1175);
DISPLAY 1.021277 (2475 1175);
DISPLAY INVISIBLE (2475 1175);
FORCEADD Q_RES..2
(2375 1575);
FORCEPROP 1 LAST PART_NUMBER CS24702JB10
J 0
(2415 1400);
DISPLAY 0.638298 (2415 1400);
DISPLAY INVISIBLE (2415 1400);
FORCEPROP 1 LAST VALUE 4.7K
J 0
(2420 1650);
DISPLAY 0.638298 (2420 1650);
FORCEPROP 1 LAST TOLERANCE 5%
J 0
(2420 1600);
DISPLAY 0.638298 (2420 1600);
FORCEPROP 1 LAST PACK_TYPE 0402LF
J 0
(2415 1450);
DISPLAY 0.638298 (2415 1450);
FORCEPROP 1 LAST WATTAGE 1/16W
J 0
(2415 1550);
DISPLAY 0.638298 (2415 1550);
FORCEPROP 1 LAST MATERIAL CHIP
J 0
(2415 1500);
DISPLAY 0.638298 (2415 1500);
FORCEPROP 1 LAST $LOCATION R3532
J 0
(2420 1700);
DISPLAY 0.638298 (2420 1700);
FORCEPROP 1 LASTPIN (2375 1675) $PN 1
J 0
(2380 1637);
DISPLAY 0.787234 (2380 1637);
FORCEPROP 1 LASTPIN (2375 1475) $PN 2
J 0
(2380 1485);
DISPLAY 0.787234 (2380 1485);
FORCEPROP 1 LAST PATH I78
J 0
(2425 1750);
DISPLAY 0.978723 (2425 1750);
PAINT WHITE (2425 1750);
DISPLAY INVISIBLE (2425 1750);
FORCEPROP 2 LAST CDS_LIB pure_quanta
J 0
(2375 1575);
PAINT MONO (2375 1575);
DISPLAY INVISIBLE (2375 1575);
FORCEPROP 2 LAST CDS_LOCATION R3532
J 0
(2425 1800);
DISPLAY 1.021277 (2425 1800);
DISPLAY INVISIBLE (2425 1800);
FORCEPROP 2 LAST $SEC 1
J 0
(2425 1800);
DISPLAY 0.680851 (2425 1800);
PAINT MONO (2425 1800);
DISPLAY INVISIBLE (2425 1800);
FORCEPROP 2 LAST CDS_SEC 1
J 0
(2425 1800);
DISPLAY 1.021277 (2425 1800);
DISPLAY INVISIBLE (2425 1800);
FORCEADD Q_RES..2
(2125 1575);
FORCEPROP 1 LAST PART_NUMBER CS24702JB10
J 0
(2165 1400);
DISPLAY 0.638298 (2165 1400);
DISPLAY INVISIBLE (2165 1400);
FORCEPROP 1 LAST VALUE 4.7K
J 0
(2170 1650);
DISPLAY 0.638298 (2170 1650);
FORCEPROP 1 LAST MATERIAL CHIP
J 0
(2165 1500);
DISPLAY 0.638298 (2165 1500);
FORCEPROP 1 LAST PACK_TYPE 0402LF
J 0
(2165 1450);
DISPLAY 0.638298 (2165 1450);
FORCEPROP 1 LAST TOLERANCE 5%
J 0
(2170 1600);
DISPLAY 0.638298 (2170 1600);
FORCEPROP 1 LAST WATTAGE 1/16W
J 0
(2165 1550);
DISPLAY 0.638298 (2165 1550);
FORCEPROP 1 LAST $LOCATION R3530
J 0
(2170 1700);
DISPLAY 0.638298 (2170 1700);
FORCEPROP 1 LASTPIN (2125 1675) $PN 1
J 0
(2130 1637);
DISPLAY 0.787234 (2130 1637);
FORCEPROP 1 LASTPIN (2125 1475) $PN 2
J 0
(2130 1485);
DISPLAY 0.787234 (2130 1485);
FORCEPROP 1 LAST PATH I80
J 0
(2175 1750);
DISPLAY 0.978723 (2175 1750);
PAINT WHITE (2175 1750);
DISPLAY INVISIBLE (2175 1750);
FORCEPROP 2 LAST CDS_LIB pure_quanta
J 0
(2125 1575);
PAINT MONO (2125 1575);
DISPLAY INVISIBLE (2125 1575);
FORCEPROP 2 LAST CDS_LOCATION R3530
J 0
(2175 1800);
DISPLAY 1.021277 (2175 1800);
DISPLAY INVISIBLE (2175 1800);
FORCEPROP 2 LAST $SEC 1
J 0
(2175 1800);
DISPLAY 0.680851 (2175 1800);
PAINT MONO (2175 1800);
DISPLAY INVISIBLE (2175 1800);
FORCEPROP 2 LAST CDS_SEC 1
J 0
(2175 1800);
DISPLAY 1.021277 (2175 1800);
DISPLAY INVISIBLE (2175 1800);
FORCEADD Q_CAP..1
(1600 1650);
FORCEPROP 1 LAST PART_NUMBER CH4104K1B00
J 0
(1650 1500);
DISPLAY 0.510638 (1650 1500);
DISPLAY INVISIBLE (1650 1500);
FORCEPROP 1 LAST PACK_TYPE 0402
J 0
(1650 1450);
DISPLAY 0.510638 (1650 1450);
FORCEPROP 1 LAST VOLTAGE 25V
J 0
(1650 1650);
DISPLAY 0.510638 (1650 1650);
FORCEPROP 1 LAST MATERIAL X7R
J 0
(1650 1550);
DISPLAY 0.510638 (1650 1550);
FORCEPROP 1 LAST TOLERANCE 10%
J 0
(1650 1600);
DISPLAY 0.510638 (1650 1600);
FORCEPROP 1 LAST VALUE 0.1UF
J 0
(1650 1700);
DISPLAY 0.510638 (1650 1700);
FORCEPROP 1 LAST $LOCATION C1998
J 0
(1650 1750);
DISPLAY 0.978723 (1650 1750);
FORCEPROP 1 LASTPIN (1600 1750) $PN 1
J 0
(1610 1730);
DISPLAY 0.787234 (1610 1730);
FORCEPROP 1 LASTPIN (1600 1550) $PN 2
J 0
(1610 1530);
DISPLAY 0.787234 (1610 1530);
FORCEPROP 1 LAST PATH I82
J 0
(1650 1800);
DISPLAY 0.978723 (1650 1800);
PAINT WHITE (1650 1800);
DISPLAY INVISIBLE (1650 1800);
FORCEPROP 2 LAST CDS_LIB pure_quanta
J 0
(1600 1650);
PAINT MONO (1600 1650);
DISPLAY INVISIBLE (1600 1650);
FORCEPROP 2 LAST CDS_LOCATION C1998
J 0
(1650 1850);
DISPLAY 1.021277 (1650 1850);
DISPLAY INVISIBLE (1650 1850);
FORCEPROP 2 LAST $SEC 1
J 0
(1650 1850);
DISPLAY 0.680851 (1650 1850);
PAINT MONO (1650 1850);
DISPLAY INVISIBLE (1650 1850);
FORCEPROP 2 LAST CDS_SEC 1
J 0
(1650 1850);
DISPLAY 1.021277 (1650 1850);
DISPLAY INVISIBLE (1650 1850);
FORCEADD UNIVERSAL_GND..1
(1600 1425);
FORCEPROP 3 LASTPIN (1600 1475) SIG_NAME GND\g
J 0
(1610 1485);
DISPLAY 0.659574 (1610 1485);
PAINT MONO (1610 1485);
DISPLAY INVISIBLE (1610 1485);
FORCEPROP 1 LAST PATH I84
J 0
(1675 1425);
DISPLAY 0.872340 (1675 1425);
PAINT AQUA (1675 1425);
DISPLAY INVISIBLE (1675 1425);
FORCEPROP 2 LAST CDS_LIB logical_power
J 0
(1600 1425);
PAINT MONO (1600 1425);
DISPLAY INVISIBLE (1600 1425);
FORCEPROP 1 LAST HDL_POWER GND
J 1
(1625 1350);
DISPLAY 0.872340 (1625 1350);
PAINT GREEN (1625 1350);
DISPLAY INVISIBLE (1625 1350);
FORCEADD UNIVERSAL_POWER..1
(75 1975);
FORCEPROP 3 LASTPIN (75 1925) SIG_NAME P3V3_AUX\g
J 0
(85 1935);
DISPLAY 0.659574 (85 1935);
PAINT MONO (85 1935);
DISPLAY INVISIBLE (85 1935);
FORCEPROP 1 LAST HDL_POWER P3V3_AUX
J 1
(75 2025);
DISPLAY 0.872340 (75 2025);
PAINT GREEN (75 2025);
FORCEPROP 1 LAST PATH I87
J 0
(125 2000);
DISPLAY 0.872340 (125 2000);
PAINT AQUA (125 2000);
DISPLAY INVISIBLE (125 2000);
FORCEPROP 2 LAST CDS_LIB logical_power
J 0
(75 1975);
PAINT MONO (75 1975);
DISPLAY INVISIBLE (75 1975);
FORCEADD Q_CAP..1
R 2
(-350 1625);
FORCEPROP 1 LAST PART_NUMBER CH4104K1B00
J 2
(-400 1475);
DISPLAY 0.510638 (-400 1475);
DISPLAY INVISIBLE (-400 1475);
FORCEPROP 1 LAST PACK_TYPE 0402
J 2
(-400 1425);
DISPLAY 0.510638 (-400 1425);
FORCEPROP 1 LAST VOLTAGE 25V
J 2
(-400 1625);
DISPLAY 0.510638 (-400 1625);
FORCEPROP 1 LAST VALUE 0.1UF
J 2
(-400 1675);
DISPLAY 0.510638 (-400 1675);
FORCEPROP 1 LAST TOLERANCE 10%
J 2
(-400 1575);
DISPLAY 0.510638 (-400 1575);
FORCEPROP 1 LAST MATERIAL X7R
J 2
(-400 1525);
DISPLAY 0.510638 (-400 1525);
FORCEPROP 1 LAST $LOCATION C1997
J 2
(-400 1725);
DISPLAY 0.978723 (-400 1725);
FORCEPROP 1 LASTPIN (-350 1725) $PN 1
J 2
(-360 1705);
DISPLAY 0.787234 (-360 1705);
FORCEPROP 1 LASTPIN (-350 1525) $PN 2
J 2
(-360 1505);
DISPLAY 0.787234 (-360 1505);
FORCEPROP 1 LAST PATH I89
J 2
(-400 1775);
DISPLAY 0.978723 (-400 1775);
PAINT WHITE (-400 1775);
DISPLAY INVISIBLE (-400 1775);
FORCEPROP 2 LAST CDS_LIB pure_quanta
J 2
(-350 1625);
PAINT MONO (-350 1625);
DISPLAY INVISIBLE (-350 1625);
FORCEPROP 2 LAST CDS_LOCATION C1997
J 0
(-400 1825);
DISPLAY 1.021277 (-400 1825);
DISPLAY INVISIBLE (-400 1825);
FORCEPROP 2 LAST $SEC 1
J 0
(-400 1825);
DISPLAY 0.680851 (-400 1825);
PAINT MONO (-400 1825);
DISPLAY INVISIBLE (-400 1825);
FORCEPROP 2 LAST CDS_SEC 1
J 0
(-400 1825);
DISPLAY 1.021277 (-400 1825);
DISPLAY INVISIBLE (-400 1825);
FORCEADD UNIVERSAL_GND..1
(-350 1425);
FORCEPROP 3 LASTPIN (-350 1475) SIG_NAME GND\g
J 0
(-340 1485);
DISPLAY 0.659574 (-340 1485);
PAINT MONO (-340 1485);
DISPLAY INVISIBLE (-340 1485);
FORCEPROP 1 LAST PATH I90
J 0
(-275 1425);
DISPLAY 0.872340 (-275 1425);
PAINT AQUA (-275 1425);
DISPLAY INVISIBLE (-275 1425);
FORCEPROP 2 LAST CDS_LIB logical_power
J 0
(-350 1425);
PAINT MONO (-350 1425);
DISPLAY INVISIBLE (-350 1425);
FORCEPROP 1 LAST HDL_POWER GND
J 1
(-325 1350);
DISPLAY 0.872340 (-325 1350);
PAINT GREEN (-325 1350);
DISPLAY INVISIBLE (-325 1350);
FORCEADD OFFPAGE..6
(-925 1125);
FORCEPROP 2 LAST $XR0 231 
J 0
(-1205 1125);
DISPLAY 0.638298 (-1205 1125);
PAINT MONO (-1205 1125);
FORCEPROP 2 LAST PATH I91
J 0
(-1200 1175);
DISPLAY 1.021277 (-1200 1175);
DISPLAY INVISIBLE (-1200 1175);
FORCEPROP 2 LAST CDS_LIB standard
J 0
(-925 1125);
PAINT MONO (-925 1125);
DISPLAY INVISIBLE (-925 1125);
FORCEPROP 1 LAST OFFPAGE TRUE
J 0
(-600 1000);
DISPLAY 0.872340 (-600 1000);
DISPLAY INVISIBLE (-600 1000);
FORCEPROP 1 LAST COMMENT_BODY TRUE
J 0
(-825 1050);
DISPLAY 0.872340 (-825 1050);
PAINT GREEN (-825 1050);
DISPLAY INVISIBLE (-825 1050);
FORCEADD OFFPAGE..1
(-925 1225);
FORCEPROP 2 LAST $XR0 231 
J 0
(-1177 1225);
DISPLAY 0.638298 (-1177 1225);
PAINT MONO (-1177 1225);
FORCEPROP 2 LAST PATH I92
J 0
(-1200 1275);
DISPLAY 1.021277 (-1200 1275);
DISPLAY INVISIBLE (-1200 1275);
FORCEPROP 1 LAST COMMENT_BODY TRUE
J 0
(-800 1125);
DISPLAY 0.872340 (-800 1125);
PAINT GREEN (-800 1125);
DISPLAY INVISIBLE (-800 1125);
FORCEPROP 1 LAST OFFPAGE TRUE
J 0
(-600 1100);
DISPLAY 0.872340 (-600 1100);
DISPLAY INVISIBLE (-600 1100);
FORCEPROP 2 LAST CDS_LIB standard
J 0
(-925 1225);
PAINT MONO (-925 1225);
DISPLAY INVISIBLE (-925 1225);
FORCEADD PCA9617ADP..1
R 2
(850 1175);
FORCEPROP 1 LAST PART_NUMBER AL009617K02
J 2
(1124 1535);
DISPLAY 0.723404 (1124 1535);
PAINT GREEN (1124 1535);
DISPLAY INVISIBLE (1124 1535);
FORCEPROP 1 LAST MATERIAL IC
J 2
(1124 1480);
DISPLAY 0.723404 (1124 1480);
PAINT GREEN (1124 1480);
FORCEPROP 2 LAST PART_TYPE SMLF
J 2
(1100 1675);
DISPLAY 1.021277 (1100 1675);
FORCEPROP 2 LAST VALUE PCA9617ADP
J 2
(1100 1625);
DISPLAY 1.021277 (1100 1625);
FORCEPROP 1 LAST $LOCATION U279
J 2
(1124 1585);
DISPLAY 0.723404 (1124 1585);
PAINT GREEN (1124 1585);
FORCEPROP 0 LASTPIN (425 975) $PN 5
J 2
(415 985);
DISPLAY 0.680851 (415 985);
PAINT MONO (415 985);
FORCEPROP 0 LASTPIN (1275 975) $PN 4
J 0
(1285 985);
DISPLAY 0.680851 (1285 985);
PAINT MONO (1285 985);
FORCEPROP 0 LASTPIN (1275 1225) $PN 2
J 0
(1285 1235);
DISPLAY 0.680851 (1285 1235);
PAINT MONO (1285 1235);
FORCEPROP 0 LASTPIN (425 1225) $PN 7
J 2
(415 1235);
DISPLAY 0.680851 (415 1235);
PAINT MONO (415 1235);
FORCEPROP 0 LASTPIN (1275 1125) $PN 3
J 0
(1285 1135);
DISPLAY 0.680851 (1285 1135);
PAINT MONO (1285 1135);
FORCEPROP 0 LASTPIN (425 1125) $PN 6
J 2
(415 1135);
DISPLAY 0.680851 (415 1135);
PAINT MONO (415 1135);
FORCEPROP 0 LASTPIN (1275 1375) $PN 1
J 0
(1285 1385);
DISPLAY 0.680851 (1285 1385);
PAINT MONO (1285 1385);
FORCEPROP 0 LASTPIN (425 1375) $PN 8
J 2
(415 1385);
DISPLAY 0.680851 (415 1385);
PAINT MONO (415 1385);
FORCEPROP 1 LAST PATH I93
J 2
(850 1175);
DISPLAY 0.723404 (850 1175);
PAINT GREEN (850 1175);
DISPLAY INVISIBLE (850 1175);
FORCEPROP 1 LAST NEEDS_NO_SIZE TRUE
J 2
(575 875);
DISPLAY 0.468085 (575 875);
PAINT GREEN (575 875);
DISPLAY INVISIBLE (575 875);
FORCEPROP 1 LAST CDS_LMAN_SYM_OUTLINE -275,300,275,-300
J 2
(850 1175);
DISPLAY 0.468085 (850 1175);
PAINT GREEN (850 1175);
DISPLAY INVISIBLE (850 1175);
FORCEPROP 2 LAST CDS_LIB pure_quanta
J 2
(850 1175);
DISPLAY INVISIBLE (850 1175);
FORCEPROP 0 LAST CDS_LOCATION U279
J 0
(1100 1725);
DISPLAY 1.021277 (1100 1725);
DISPLAY INVISIBLE (1100 1725);
FORCEPROP 0 LAST $SEC 1
J 0
(1100 1725);
DISPLAY 0.680851 (1100 1725);
PAINT MONO (1100 1725);
DISPLAY INVISIBLE (1100 1725);
FORCEPROP 0 LAST CDS_SEC 1
J 0
(1100 1725);
DISPLAY 1.021277 (1100 1725);
DISPLAY INVISIBLE (1100 1725);
FORCEADD OFFPAGE..4
R 2
(-2300 975);
FORCEPROP 2 LAST $XR0 191 
J 0
(-2582 975);
DISPLAY 0.638298 (-2582 975);
PAINT MONO (-2582 975);
FORCEPROP 2 LAST PATH I94
J 2
(-2850 1025);
DISPLAY 1.021277 (-2850 1025);
DISPLAY INVISIBLE (-2850 1025);
FORCEPROP 1 LAST COMMENT_BODY TRUE
J 2
(-2275 875);
DISPLAY 0.872340 (-2275 875);
PAINT GREEN (-2275 875);
DISPLAY INVISIBLE (-2275 875);
FORCEPROP 1 LAST OFFPAGE TRUE
J 2
(-2625 850);
DISPLAY 0.872340 (-2625 850);
DISPLAY INVISIBLE (-2625 850);
FORCEPROP 2 LAST CDS_LIB standard
J 2
(-2300 975);
DISPLAY INVISIBLE (-2300 975);
FORCEADD UNIVERSAL_GND..1
(1450 850);
FORCEPROP 3 LASTPIN (1450 900) SIG_NAME GND\g
J 0
(1460 910);
DISPLAY 0.659574 (1460 910);
PAINT MONO (1460 910);
DISPLAY INVISIBLE (1460 910);
FORCEPROP 1 LAST PATH I95
J 0
(1525 850);
DISPLAY 0.872340 (1525 850);
PAINT AQUA (1525 850);
DISPLAY INVISIBLE (1525 850);
FORCEPROP 2 LAST CDS_LIB logical_power
J 0
(1450 850);
PAINT MONO (1450 850);
DISPLAY INVISIBLE (1450 850);
FORCEPROP 1 LAST HDL_POWER GND
J 1
(1475 775);
DISPLAY 0.872340 (1475 775);
PAINT GREEN (1475 775);
DISPLAY INVISIBLE (1475 775);
FORCEADD Q_RES..1
(-1500 975);
FORCEPROP 1 LAST PART_NUMBER CS42002FB05
J 0
(-1600 1050);
DISPLAY 0.510638 (-1600 1050);
DISPLAY INVISIBLE (-1600 1050);
FORCEPROP 1 LAST MATERIAL EMPTY
J 0
(-1200 975);
DISPLAY 0.510638 (-1200 975);
PAINT RED (-1200 975);
FORCEPROP 1 LAST TOLERANCE 1%
J 0
(-1275 975);
DISPLAY 0.510638 (-1275 975);
FORCEPROP 1 LAST VALUE 200K
J 2
(-1300 975);
DISPLAY 0.510638 (-1300 975);
FORCEPROP 1 LAST WATTAGE 1/16W
J 2
(-1325 1075);
DISPLAY 0.510638 (-1325 1075);
FORCEPROP 1 LAST PACK_TYPE 0402LF
J 0
(-1600 1075);
DISPLAY 0.510638 (-1600 1075);
FORCEPROP 1 LAST $LOCATION R3531
J 0
(-1725 975);
DISPLAY 0.787234 (-1725 975);
FORCEPROP 1 LASTPIN (-1600 975) $PN 1
J 0
(-1588 987);
DISPLAY 0.787234 (-1588 987);
PAINT MONO (-1588 987);
FORCEPROP 1 LASTPIN (-1400 975) $PN 2
J 0
(-1438 987);
DISPLAY 0.787234 (-1438 987);
PAINT MONO (-1438 987);
FORCEPROP 1 LAST PATH I96
J 0
(-1550 1125);
DISPLAY 0.978723 (-1550 1125);
PAINT WHITE (-1550 1125);
DISPLAY INVISIBLE (-1550 1125);
FORCEPROP 2 LAST CDS_LIB pure_quanta
J 0
(-1500 975);
DISPLAY INVISIBLE (-1500 975);
FORCEPROP 0 LAST CDS_LOCATION R3531
J 0
(-1300 1125);
DISPLAY 1.021277 (-1300 1125);
DISPLAY INVISIBLE (-1300 1125);
FORCEPROP 0 LAST $SEC 1
J 0
(-1300 1125);
DISPLAY 0.680851 (-1300 1125);
PAINT MONO (-1300 1125);
DISPLAY INVISIBLE (-1300 1125);
FORCEPROP 0 LAST CDS_SEC 1
J 0
(-1300 1125);
DISPLAY 1.021277 (-1300 1125);
DISPLAY INVISIBLE (-1300 1125);
FORCEADD UNIVERSAL_POWER..1
(1425 1950);
FORCEPROP 3 LASTPIN (1425 1900) SIG_NAME P3V3_E1S_0\g
J 0
(1435 1910);
DISPLAY 0.659574 (1435 1910);
PAINT MONO (1435 1910);
DISPLAY INVISIBLE (1435 1910);
FORCEPROP 1 LAST HDL_POWER P3V3_E1S_0
J 1
(1425 2000);
DISPLAY 0.872340 (1425 2000);
PAINT GREEN (1425 2000);
FORCEPROP 1 LAST PATH I97
J 0
(1475 1975);
DISPLAY 0.872340 (1475 1975);
PAINT AQUA (1475 1975);
DISPLAY INVISIBLE (1475 1975);
FORCEPROP 2 LAST CDS_LIB logical_power
J 0
(1425 1950);
DISPLAY INVISIBLE (1425 1950);
FORCEADD UNIVERSAL_POWER..1
(2125 1900);
FORCEPROP 3 LASTPIN (2125 1850) SIG_NAME P3V3_E1S_0\g
J 0
(2135 1860);
DISPLAY 0.659574 (2135 1860);
PAINT MONO (2135 1860);
DISPLAY INVISIBLE (2135 1860);
FORCEPROP 1 LAST HDL_POWER P3V3_E1S_0
J 1
(2125 1950);
DISPLAY 0.872340 (2125 1950);
PAINT GREEN (2125 1950);
FORCEPROP 1 LAST PATH I98
J 0
(2175 1925);
DISPLAY 0.872340 (2175 1925);
PAINT AQUA (2175 1925);
DISPLAY INVISIBLE (2175 1925);
FORCEPROP 2 LAST CDS_LIB logical_power
J 0
(2125 1900);
DISPLAY INVISIBLE (2125 1900);
FORCEADD Q_RES..2
(-25 1600);
FORCEPROP 1 LAST PART_NUMBER CS31002FB08
J 0
(25 1550);
DISPLAY 0.510638 (25 1550);
DISPLAY INVISIBLE (25 1550);
FORCEPROP 1 LAST TOLERANCE 1%
J 0
(25 1625);
DISPLAY 0.510638 (25 1625);
FORCEPROP 1 LAST MATERIAL CHIP
J 0
(25 1575);
DISPLAY 0.510638 (25 1575);
FORCEPROP 1 LAST PACK_TYPE 0402LF
J 0
(25 1525);
DISPLAY 0.510638 (25 1525);
FORCEPROP 1 LAST VALUE 10K
J 0
(25 1650);
DISPLAY 0.510638 (25 1650);
FORCEPROP 1 LAST WATTAGE 1/16W
J 0
(25 1600);
DISPLAY 0.510638 (25 1600);
FORCEPROP 1 LAST LOCATION R3529
J 0
(25 1675);
DISPLAY 0.638298 (25 1675);
FORCEPROP 1 LASTPIN (-25 1700) $PN 1
J 0
(-20 1662);
DISPLAY 0.787234 (-20 1662);
PAINT MONO (-20 1662);
FORCEPROP 1 LASTPIN (-25 1500) $PN 2
J 0
(-20 1510);
DISPLAY 0.787234 (-20 1510);
PAINT MONO (-20 1510);
FORCEPROP 2 LAST CDS_LIB pure_quanta
J 0
(-25 1600);
DISPLAY INVISIBLE (-25 1600);
FORCEPROP 1 LAST PATH I99
J 0
(25 1775);
DISPLAY 0.978723 (25 1775);
PAINT WHITE (25 1775);
DISPLAY INVISIBLE (25 1775);
FORCEPROP 0 LAST $SEC 1
J 0
(25 1725);
DISPLAY 0.680851 (25 1725);
PAINT MONO (25 1725);
DISPLAY INVISIBLE (25 1725);
FORCEPROP 0 LAST CDS_SEC 1
J 0
(25 1725);
DISPLAY 1.021277 (25 1725);
DISPLAY INVISIBLE (25 1725);
FORCEADD DNS..2
(-2100 -225);
PAINT RED (-2100 -225);
FORCEPROP 1 LAST COMMENT_BODY TRUE
J 0
(-2100 -225);
DISPLAY INVISIBLE (-2100 -225);
FORCEPROP 2 LAST CDS_LIB mstr_misc
J 0
(-2100 -225);
DISPLAY INVISIBLE (-2100 -225);
FORCEADD DNS..2
(-1475 975);
PAINT RED (-1475 975);
FORCEPROP 2 LAST CDS_LIB mstr_misc
J 0
(-1475 975);
DISPLAY INVISIBLE (-1475 975);
FORCEPROP 1 LAST COMMENT_BODY TRUE
J 0
(-1475 975);
DISPLAY INVISIBLE (-1475 975);
FORCEADD DNS..2
(2325 3100);
PAINT RED (2325 3100);
FORCEPROP 2 LAST CDS_LIB mstr_misc
J 0
(2325 3100);
DISPLAY INVISIBLE (2325 3100);
FORCEPROP 1 LAST COMMENT_BODY TRUE
J 0
(2325 3100);
DISPLAY INVISIBLE (2325 3100);
FORCEADD QUANTA_TITLE_BLOCK_C..1
(5950 -1750);
FORCEPROP 0 LAST CDS_CON_LAST_MODIFIED Fri Aug 25 14:03:08 2023
J 0
(4065 -1735);
PAINT MONO (4065 -1735);
DISPLAY INVISIBLE (4065 -1735);
FORCEPROP 1 LAST CUSTOM_TXT_CDS <CON_LAST_MODIFIED>
J 0
(4065 -1735);
DISPLAY 0.978723 (4065 -1735);
FORCEPROP 2 LAST CUSTOM_TXT_CDS <XR_PAGE_TITLE>
J 0
(-1940 3500);
DISPLAY 0.638298 (-1940 3500);
PAINT PINK (-1940 3500);
DISPLAY INVISIBLE (-1940 3500);
FORCEPROP 1 LAST CUSTOM_TXT_CDS <NAME_2>
J 0
(2775 -1700);
FORCEPROP 1 LAST CUSTOM_TXT_CDS <NAME_1>
J 0
(2775 -1575);
FORCEPROP 1 LAST CUSTOM_TXT_CDS <Q_NUMBER>
J 0
(4547 -1647);
DISPLAY 1.212766 (4547 -1647);
FORCEPROP 1 LAST CUSTOM_TXT_CDS <Q_PROJ>
J 0
(3568 -1648);
DISPLAY 1.212766 (3568 -1648);
FORCEPROP 1 LAST CUSTOM_TXT_CDS <Q_REV>
J 0
(5766 -1647);
DISPLAY 1.212766 (5766 -1647);
FORCEPROP 1 LAST CUSTOM_TXT_CDS <CON_PAGE_NUM> OF <CON_TOTAL_PAGES>
J 0
(5504 -1732);
DISPLAY 0.978723 (5504 -1732);
FORCEPROP 1 LAST Q_TITLE PCH - SATA / RAID KEY
J 0
(-3341 -1724);
DISPLAY 2.446809 (-3341 -1724);
PAINT GREEN (-3341 -1724);
FORCEPROP 1 LAST Q_DEPT 
J 1
(2187 -1701);
DISPLAY 1.957447 (2187 -1701);
PAINT GREEN (2187 -1701);
FORCEPROP 2 LAST CDS_XR_PAGE_TITLE CR-194 : @S9S_MB_2U_LIB.S9S_MB_2U(SCH_1):PAGE194
J 0
(-1940 3500);
DISPLAY 0.638298 (-1940 3500);
PAINT PINK (-1940 3500);
DISPLAY INVISIBLE (-1940 3500);
FORCEPROP 2 LAST CDS_LIB pure_quanta
J 0
(5950 -1750);
PAINT MONO (5950 -1750);
DISPLAY INVISIBLE (5950 -1750);
FORCEPROP 1 LAST CDS_LMAN_SYM_OUTLINE -9475,6775,100,-125
J 0
(5950 -1750);
DISPLAY 0.468085 (5950 -1750);
PAINT GREEN (5950 -1750);
DISPLAY INVISIBLE (5950 -1750);
FORCEPROP 2 LAST PAGE_BORDER TRUE
J 0
(-1940 3500);
DISPLAY 0.638298 (-1940 3500);
PAINT PINK (-1940 3500);
DISPLAY INVISIBLE (-1940 3500);
FORCEPROP 1 LAST COMMENT_BODY TRUE
J 0
(5962 -1763);
DISPLAY 0.978723 (5962 -1763);
PAINT GREEN (5962 -1763);
DISPLAY INVISIBLE (5962 -1763);
WIRE 16 -1 (-2100 -100)(-2100 175);
WIRE 16 -1 (1425 1825)(1425 1900);
WIRE 16 -1 (1425 1825)(1425 1375);
WIRE 16 -1 (1425 1825)(1600 1825);
WIRE 16 -1 (75 1925)(75 1800);
WIRE 16 -1 (1225 3975)(1225 4050);
WIRE 16 -1 (1225 3975)(1400 3975);
WIRE 16 -1 (1225 3975)(1225 3525);
WIRE 16 -1 (2125 1800)(2125 1850);
WIRE 16 -1 (2125 1800)(2375 1800);
WIRE 16 -1 (2125 1675)(2125 1800);
WIRE 16 -1 (0 4075)(0 3950);
WIRE 16 -1 (2250 4000)(2250 4050);
WIRE 16 -1 (2250 4000)(2500 4000);
WIRE 16 -1 (2250 3875)(2250 4000);
WIRE 16 -1 (-350 1525)(-350 1475);
WIRE 16 -1 (1450 900)(1450 975);
WIRE 16 -1 (1600 1550)(1600 1475);
WIRE 16 -1 (-425 3675)(-425 3625);
WIRE 16 -1 (350 3200)(350 3275);
WIRE 16 -1 (1400 3700)(1400 3625);
WIRE 16 2175 (-150 1325)(500 1325);
WIRE 16 2175 (500 2100)(500 1325);
WIRE 16 2175 (-150 2100)(-150 1325);
WIRE 16 2175 (-150 2100)(500 2100);
WIRE 16 -1 (-350 1725)(-350 1800);
WIRE 16 -1 (-350 1800)(-25 1800);
WIRE 16 -1 (-25 1800)(-25 1700);
WIRE 16 -1 (-25 1800)(75 1800);
WIRE 16 -1 (75 1800)(350 1800);
WIRE 16 -1 (350 1800)(350 1375);
WIRE 16 -1 (425 1375)(350 1375);
WIRE 16 -1 (1600 1750)(1600 1825);
WIRE 16 -1 (1425 1375)(1275 1375);
WIRE 16 -1 (2125 1225)(1275 1225);
FORCEPROP 0 LAST CDS_PHYS_NET_NAME SMB_SENSOR_M2_P0_3V3AUX_SCL
J 0
(1490 1273);
PAINT MONO (1490 1273);
DISPLAY INVISIBLE (1490 1273);
FORCEPROP 2 LAST SIG_NAME SMB_E1S_3V3AUX_ISO_SCL_R
J 0
(1490 1235);
DISPLAY 0.510638 (1490 1235);
PAINT WHITE (1490 1235);
WIRE 16 -1 (2125 1475)(2125 1225);
WIRE 16 -1 (2600 1225)(2125 1225);
WIRE 16 -1 (-25 975)(-1400 975);
FORCEPROP 0 LAST CDS_PHYS_NET_NAME SMB_PCIE_M2_1_EN
J 0
(-460 1023);
PAINT MONO (-460 1023);
DISPLAY INVISIBLE (-460 1023);
FORCEPROP 2 LAST SIG_NAME SMB_PCIE_E1S_ISO_EN_R
J 0
(-710 985);
DISPLAY 0.510638 (-710 985);
PAINT WHITE (-710 985);
WIRE 16 -1 (-25 1500)(-25 975);
WIRE 16 -1 (425 975)(-25 975);
WIRE 16 -1 (425 1125)(-875 1125);
FORCEPROP 0 LAST CDS_PHYS_NET_NAME SMB_SENSOR_M2_P0_3V3AUX_SCL
J 0
(-760 1173);
PAINT MONO (-760 1173);
DISPLAY INVISIBLE (-760 1173);
FORCEPROP 2 LAST SIG_NAME SMB_SENSOR_E1S_3V3AUX_SDA
J 2
(-110 1135);
DISPLAY 0.510638 (-110 1135);
PAINT WHITE (-110 1135);
WIRE 16 -1 (425 1225)(-875 1225);
FORCEPROP 0 LAST CDS_PHYS_NET_NAME SMB_SENSOR_M2_P0_3V3AUX_SDA
J 0
(-760 1273);
PAINT MONO (-760 1273);
DISPLAY INVISIBLE (-760 1273);
FORCEPROP 2 LAST SIG_NAME SMB_SENSOR_E1S_3V3AUX_SCL
J 2
(-110 1235);
DISPLAY 0.510638 (-110 1235);
PAINT WHITE (-110 1235);
WIRE 16 -1 (2375 1125)(1275 1125);
FORCEPROP 0 LAST CDS_PHYS_NET_NAME SMB_SENSOR_M2_P0_3V3AUX_SDA
J 0
(2015 1173);
PAINT MONO (2015 1173);
DISPLAY INVISIBLE (2015 1173);
FORCEPROP 2 LAST SIG_NAME SMB_E1S_3V3AUX_ISO_SDA_R
J 0
(1490 1135);
DISPLAY 0.510638 (1490 1135);
PAINT WHITE (1490 1135);
WIRE 16 -1 (2375 1475)(2375 1125);
WIRE 16 -1 (2600 1125)(2375 1125);
WIRE 16 -1 (1075 3275)(1975 3275);
FORCEPROP 0 LAST CDS_PHYS_NET_NAME SMB_SENSOR_M2_P0_3V3AUX_SDA
J 0
(1190 3323);
PAINT MONO (1190 3323);
DISPLAY INVISIBLE (1190 3323);
FORCEPROP 2 LAST SIG_NAME SMB_PCIE_M2_0_EN
J 0
(1225 3285);
DISPLAY 0.510638 (1225 3285);
PAINT WHITE (1225 3285);
WIRE 16 -1 (1975 3100)(1975 3275);
WIRE 16 -1 (2200 3100)(1975 3100);
WIRE 16 -1 (0 3100)(1975 3100);
WIRE 16 -1 (0 3525)(0 3100);
WIRE 16 -1 (0 3650)(0 3525);
WIRE 16 -1 (375 3525)(0 3525);
WIRE 16 -1 (2500 3375)(1075 3375);
FORCEPROP 0 LAST CDS_PHYS_NET_NAME SMB_SENSOR_M2_P0_3V3AUX_SDA
J 0
(1190 3423);
PAINT MONO (1190 3423);
DISPLAY INVISIBLE (1190 3423);
FORCEPROP 2 LAST SIG_NAME SMB_M2_P0_1V8AUX_SCL_R
J 0
(1225 3385);
DISPLAY 0.510638 (1225 3385);
PAINT WHITE (1225 3385);
WIRE 16 -1 (2500 3675)(2500 3375);
WIRE 16 -1 (2700 3375)(2500 3375);
WIRE 16 -1 (2500 3875)(2500 4000);
WIRE 16 -1 (2250 3425)(1075 3425);
FORCEPROP 0 LAST CDS_PHYS_NET_NAME SMB_SENSOR_M2_P0_3V3AUX_SCL
J 0
(1190 3473);
PAINT MONO (1190 3473);
DISPLAY INVISIBLE (1190 3473);
FORCEPROP 2 LAST SIG_NAME SMB_M2_P0_1V8AUX_SDA_R
J 0
(1225 3435);
DISPLAY 0.510638 (1225 3435);
PAINT WHITE (1225 3435);
WIRE 16 -1 (2250 3675)(2250 3425);
WIRE 16 -1 (2700 3425)(2250 3425);
WIRE 16 -1 (1225 3525)(1075 3525);
WIRE 16 -1 (1400 3900)(1400 3975);
WIRE 16 -1 (375 3375)(-950 3375);
FORCEPROP 0 LAST CDS_PHYS_NET_NAME SMB_SENSOR_M2_P0_3V3AUX_SDA
J 0
(-835 3423);
PAINT MONO (-835 3423);
DISPLAY INVISIBLE (-835 3423);
FORCEPROP 2 LAST SIG_NAME SMB_SENSOR_M2_P0_3V3AUX_SCL
J 2
(-160 3385);
DISPLAY 0.510638 (-160 3385);
PAINT WHITE (-160 3385);
WIRE 16 -1 (375 3425)(-950 3425);
FORCEPROP 0 LAST CDS_PHYS_NET_NAME SMB_SENSOR_M2_P0_3V3AUX_SCL
J 0
(-835 3473);
PAINT MONO (-835 3473);
DISPLAY INVISIBLE (-835 3473);
FORCEPROP 2 LAST SIG_NAME SMB_SENSOR_M2_P0_3V3AUX_SDA
J 2
(-160 3435);
DISPLAY 0.510638 (-160 3435);
PAINT WHITE (-160 3435);
WIRE 16 -1 (0 3950)(0 3850);
WIRE 16 -1 (-425 3950)(0 3950);
WIRE 16 -1 (-425 3875)(-425 3950);
WIRE 16 -1 (475 3275)(350 3275);
FORCEPROP 0 LAST VOLTAGE 0
J 0
(400 3275);
DISPLAY INVISIBLE (400 3275);
WIRE 16 -1 (1275 975)(1450 975);
WIRE 16 -1 (4000 1225)(2800 1225);
FORCEPROP 0 LAST CDS_PHYS_NET_NAME SMB_SENSOR_M2_P0_3V3AUX_SCL
J 0
(2915 1273);
PAINT MONO (2915 1273);
DISPLAY INVISIBLE (2915 1273);
FORCEPROP 2 LAST SIG_NAME SMB_E1S_3V3AUX_ISO_SCL
J 0
(3365 1235);
DISPLAY 0.510638 (3365 1235);
PAINT WHITE (3365 1235);
WIRE 16 -1 (4000 1125)(2800 1125);
FORCEPROP 0 LAST CDS_PHYS_NET_NAME SMB_SENSOR_M2_P0_3V3AUX_SDA
J 0
(2915 1173);
PAINT MONO (2915 1173);
DISPLAY INVISIBLE (2915 1173);
FORCEPROP 2 LAST SIG_NAME SMB_E1S_3V3AUX_ISO_SDA
J 0
(3365 1135);
DISPLAY 0.510638 (3365 1135);
PAINT WHITE (3365 1135);
WIRE 16 -1 (2375 1675)(2375 1800);
WIRE 16 -1 (-1600 975)(-2250 975);
FORCEPROP 0 LAST CDS_PHYS_NET_NAME PWRGD_P1V8_PCH_AUX
J 0
(-2135 1023);
PAINT MONO (-2135 1023);
DISPLAY INVISIBLE (-2135 1023);
FORCEPROP 2 LAST SIG_NAME SMB_PCIE_E1S_ISO_EN
J 0
(-2235 985);
DISPLAY 0.510638 (-2235 985);
PAINT WHITE (-2235 985);
WIRE 16 -1 (3575 3100)(2400 3100);
FORCEPROP 0 LAST CDS_PHYS_NET_NAME SMB_SENSOR_M2_P0_3V3AUX_SDA
J 0
(2515 3148);
PAINT MONO (2515 3148);
DISPLAY INVISIBLE (2515 3148);
FORCEPROP 2 LAST SIG_NAME PWRGD_P1V8_PCH_AUX
J 0
(2965 3110);
DISPLAY 0.510638 (2965 3110);
PAINT WHITE (2965 3110);
WIRE 16 -1 (-2100 -675)(-650 -675);
FORCEPROP 0 LAST CDS_PHYS_NET_NAME FM_PCH_SATA_RAID_KEY
J 0
(-1910 -633);
PAINT MONO (-1910 -633);
DISPLAY INVISIBLE (-1910 -633);
FORCEPROP 2 LAST SIG_NAME FM_PCH_SATA_RAID_KEY
J 0
(-1810 -665);
DISPLAY 0.680851 (-1810 -665);
PAINT WHITE (-1810 -665);
WIRE 16 -1 (-2100 -300)(-2100 -675);
WIRE 16 -1 (4075 3425)(2900 3425);
FORCEPROP 0 LAST CDS_PHYS_NET_NAME SMB_SENSOR_M2_P0_3V3AUX_SCL
J 0
(3015 3473);
PAINT MONO (3015 3473);
DISPLAY INVISIBLE (3015 3473);
FORCEPROP 2 LAST SIG_NAME SMB_M2_P0_1V8AUX_SDA
J 0
(3465 3435);
DISPLAY 0.510638 (3465 3435);
PAINT WHITE (3465 3435);
WIRE 16 -1 (4075 3375)(2900 3375);
FORCEPROP 0 LAST CDS_PHYS_NET_NAME SMB_SENSOR_M2_P0_3V3AUX_SDA
J 0
(3015 3423);
PAINT MONO (3015 3423);
DISPLAY INVISIBLE (3015 3423);
FORCEPROP 2 LAST SIG_NAME SMB_M2_P0_1V8AUX_SCL
J 0
(3465 3385);
DISPLAY 0.510638 (3465 3385);
PAINT WHITE (3465 3385);
DOT 1 (75 1800);
DOT 1 (-25 975);
DOT 1 (-25 1800);
DOT 1 (0 3950);
DOT 1 (2125 1800);
DOT 1 (2375 1125);
DOT 1 (2125 1225);
DOT 1 (1425 1825);
DOT 1 (2250 4000);
DOT 1 (2500 3375);
DOT 1 (2250 3425);
DOT 1 (1975 3100);
DOT 1 (1225 3975);
DOT 1 (0 3525);
FORCENOTE
20210607 MODIFY FOR GT
(-550 4475) 0;
DISPLAY LEFT (-550 4475);
DISPLAY 2.510638 (-550 4475);
PAINT PINK (-550 4475);
FORCENOTE
20210616 MODIFY FOR GT
(-3050 -1125) 0;
DISPLAY LEFT (-3050 -1125);
DISPLAY 2.510638 (-3050 -1125);
PAINT PINK (-3050 -1125);
FORCENOTE
20211130 CHANGE R3529 TO 10K OHM
(-675 2150) 0;
DISPLAY LEFT (-675 2150);
DISPLAY 1.276596 (-675 2150);
PAINT PINK (-675 2150);
QUIT
